FILE_TYPE=LIBRARY_PARTS;
primitive 'MP5991GLUZ';
  pin
    'VIN1':
      PIN_NUMBER='(9)';
      INPUT_LOAD='(-0.01,0.01)';
    'VIN2':
      PIN_NUMBER='(10)';
      INPUT_LOAD='(-0.01,0.01)';
    'VIN3':
      PIN_NUMBER='(11)';
      INPUT_LOAD='(-0.01,0.01)';
    'VIN4':
      PIN_NUMBER='(12)';
      INPUT_LOAD='(-0.01,0.01)';
    'VIN5':
      PIN_NUMBER='(13)';
      INPUT_LOAD='(-0.01,0.01)';
    'ON':
      PIN_NUMBER='(4)';
      INPUT_LOAD='(-0.01,0.01)';
    'OCREF':
      PIN_NUMBER='(24)';
      OUTPUT_LOAD='(1.0,-1.0)';
    'CS':
      PIN_NUMBER='(23)';
      OUTPUT_LOAD='(1.0,-1.0)';
    'IMON':
      PIN_NUMBER='(22)';
      OUTPUT_LOAD='(1.0,-1.0)';
    'VDD33':
      PIN_NUMBER='(21)';
      PINUSE='POWER';
      NO_LOAD_CHECK='Both';
      NO_IO_CHECK='Both';
      NO_ASSERT_CHECK='TRUE';
      NO_DIR_CHECK='TRUE';
      ALLOW_CONNECT='TRUE';
    'GND':
      PIN_NUMBER='(20)';
      PINUSE='POWER';
      NO_LOAD_CHECK='Both';
      NO_IO_CHECK='Both';
      NO_ASSERT_CHECK='TRUE';
      NO_DIR_CHECK='TRUE';
      ALLOW_CONNECT='TRUE';
    'SS':
      PIN_NUMBER='(19)';
      INPUT_LOAD='(-0.01,0.01)';
    'GOK':
      PIN_NUMBER='(5)';
      OUTPUT_LOAD='(1.0,-1.0)';
    'VTEMP':
      PIN_NUMBER='(18)';
      OUTPUT_LOAD='(1.0,-1.0)';
    'VOUT1':
      PIN_NUMBER='(1)';
      OUTPUT_LOAD='(1.0,-1.0)';
    'VOUT2':
      PIN_NUMBER='(2)';
      OUTPUT_LOAD='(1.0,-1.0)';
    'VOUT3':
      PIN_NUMBER='(25)';
      OUTPUT_LOAD='(1.0,-1.0)';
    'VOUT4':
      PIN_NUMBER='(26)';
      OUTPUT_LOAD='(1.0,-1.0)';
    'D_OC':
      PIN_NUMBER='(3)';
      OUTPUT_LOAD='(1.0,-1.0)';
    'VIN6':
      PIN_NUMBER='(14)';
      INPUT_LOAD='(-0.01,0.01)';
    'VIN7':
      PIN_NUMBER='(15)';
      INPUT_LOAD='(-0.01,0.01)';
    'VIN8':
      PIN_NUMBER='(16)';
      INPUT_LOAD='(-0.01,0.01)';
    'VIN9':
      PIN_NUMBER='(33)';
      INPUT_LOAD='(-0.01,0.01)';
    'VOUT5':
      PIN_NUMBER='(27)';
      OUTPUT_LOAD='(1.0,-1.0)';
    'VOUT6':
      PIN_NUMBER='(28)';
      OUTPUT_LOAD='(1.0,-1.0)';
    'VOUT7':
      PIN_NUMBER='(29)';
      OUTPUT_LOAD='(1.0,-1.0)';
    'VOUT8':
      PIN_NUMBER='(30)';
      OUTPUT_LOAD='(1.0,-1.0)';
    'VOUT9':
      PIN_NUMBER='(31)';
      OUTPUT_LOAD='(1.0,-1.0)';
    'VOUT10':
      PIN_NUMBER='(32)';
      OUTPUT_LOAD='(1.0,-1.0)';
    'MODE':
      PIN_NUMBER='(8)';
      INPUT_LOAD='(-0.01,0.01)';
    'SCREF_OCWREF':
      PIN_NUMBER='(17)';
      INPUT_LOAD='(-0.01,0.01)';
    'FLT_TYPE':
      PIN_NUMBER='(6)';
      INPUT_LOAD='(-0.01,0.01)';
    'NC1':
      PIN_NUMBER='(7)';
      OUTPUT_TYPE='(TS,TS)';
      INPUT_LOAD='(-0.01,0.01)';
      OUTPUT_LOAD='(1.0,-1.0)';
  end_pin;
  body
    PART_NAME='MP5991GLUZ';
    BODY_NAME='MP5991GLUZ';
    PHYS_DES_PREFIX='U';
    CLASS='IC';
  end_body;
end_primitive;

END.
